(kicad_pcb
	(version 20260206)
	(generator "pcbnew")
	(generator_version "10.0")
	(general
		(thickness 1.6)
		(legacy_teardrops no)
	)
	(paper "A4")
	(title_block
		(title "netronome-mezz — pcbd0082-001_rev01_jul9_a.brd")
		(comment 1 "Open CloudServer (Microsoft) / footprints 360-368 of 714")
	)
	(layers
		(0 "F.Cu" signal "TOP")
		(4 "In1.Cu" signal "02_GND")
		(6 "In2.Cu" signal "03_SIG")
		(8 "In3.Cu" signal "04_SIG")
		(10 "In4.Cu" signal "05_GND")
		(12 "In5.Cu" signal "06_PWR1")
		(14 "In6.Cu" signal "07_SIG")
		(16 "In7.Cu" signal "08_SIG")
		(18 "In8.Cu" signal "09_GND")
		(2 "B.Cu" signal "BOTTOM")
		(9 "F.Adhes" user "F.Adhesive")
		(11 "B.Adhes" user "B.Adhesive")
		(13 "F.Paste" user "Package Geometry/Pastemask Top")
		(15 "B.Paste" user "Package Geometry/Pastemask Bottom")
		(5 "F.SilkS" user "Ref Des/Silkscreen Top")
		(7 "B.SilkS" user "Ref Des/Silkscreen Bottom")
		(1 "F.Mask" user "Board Geometry/Soldermask Top")
		(3 "B.Mask" user "Board Geometry/Soldermask Bottom")
		(17 "Dwgs.User" user "User.Drawings")
		(19 "Cmts.User" user "User.Comments")
		(21 "Eco1.User" user "User.Eco1")
		(23 "Eco2.User" user "User.Eco2")
		(25 "Edge.Cuts" user "Board Geometry/Outline")
		(27 "Margin" user)
		(31 "F.CrtYd" user "Package Geometry/Place Bound Top")
		(29 "B.CrtYd" user "Package Geometry/Place Bound Bottom")
		(35 "F.Fab" user "Ref Des/Assembly Top")
		(33 "B.Fab" user "Ref Des/Assembly Bottom")
		(45 "User.4" user "COMPVAL_TYPE_BOTTOM")
	)
	(footprint ""
		(layer "B.Cu")
		(at 40.237029 26.542238)
		(property "Reference" "R406"
			(at 0 0 0)
			(layer "B.SilkS")
			(hide yes)
			(effects
				(font
					(size 1.27 1.27)
				)
				(justify mirror)
			)
		)
		(property "Value" ""
			(at 0 0 0)
			(layer "B.Fab")
			(effects
				(font
					(size 1.27 1.27)
				)
				(justify mirror)
			)
		)
		(duplicate_pad_numbers_are_jumpers no)
		(fp_circle
			(center 0 0)
			(end 0.104648 0)
			(stroke
				(width 0.1016)
				(type default)
			)
			(fill no)
			(layer "B.SilkS")
		)
		(fp_poly
			(pts
				(xy 0.381 -0.889) (xy 0.381 0.889) (xy -0.381 0.889) (xy -0.381 -0.889)
			)
			(stroke
				(width 0)
				(type default)
			)
			(fill no)
			(layer "B.CrtYd")
		)
		(fp_line
			(start -0.508 -1.016)
			(end -0.508 1.016)
			(stroke
				(width 0.0254)
				(type default)
			)
			(layer "B.Fab")
		)
		(fp_line
			(start -0.508 1.016)
			(end 0.508 1.016)
			(stroke
				(width 0.0254)
				(type default)
			)
			(layer "B.Fab")
		)
		(fp_line
			(start 0.254 -1.016)
			(end -0.508 -1.016)
			(stroke
				(width 0.0254)
				(type default)
			)
			(layer "B.Fab")
		)
		(fp_line
			(start 0.508 -1.016)
			(end 0.254 -1.016)
			(stroke
				(width 0.0254)
				(type default)
			)
			(layer "B.Fab")
		)
		(fp_line
			(start 0.508 1.016)
			(end 0.508 -1.016)
			(stroke
				(width 0.0254)
				(type default)
			)
			(layer "B.Fab")
		)
		(pad "1" smd custom
			(at 0 -0.500126 180)
			(size 0.127 0.127)
			(layers "B.Cu" "B.Mask" "B.Paste")
			(net "VDD_3.3V")
			(options
				(clearance outline)
				(anchor circle)
			)
			(primitives
				(gr_poly
					(pts
						(xy -0.1778 0.254) (xy 0.1778 0.254) (xy 0.254 0.1778) (xy 0.254 -0.1778) (xy 0.1778 -0.254) (xy -0.1778 -0.254)
						(xy -0.254 -0.1778) (xy -0.254 0.1778)
					)
					(width 0)
					(fill yes)
				)
			)
		)
		(pad "2" smd custom
			(at 0 0.500126 180)
			(size 0.127 0.127)
			(layers "B.Cu" "B.Mask" "B.Paste")
			(net "NFP_JTAG_ARM_TRST_L")
			(options
				(clearance outline)
				(anchor circle)
			)
			(primitives
				(gr_poly
					(pts
						(xy -0.1778 0.254) (xy 0.1778 0.254) (xy 0.254 0.1778) (xy 0.254 -0.1778) (xy 0.1778 -0.254) (xy -0.1778 -0.254)
						(xy -0.254 -0.1778) (xy -0.254 0.1778)
					)
					(width 0)
					(fill yes)
				)
			)
		)
	)
	(footprint ""
		(layer "B.Cu")
		(at 81.850992 25.813004)
		(property "Reference" "V3_A-A00"
			(at 0 0 0)
			(layer "B.SilkS")
			(hide yes)
			(effects
				(font
					(size 1.27 1.27)
				)
				(justify mirror)
			)
		)
		(property "Value" ""
			(at 0 0 0)
			(layer "B.Fab")
			(effects
				(font
					(size 1.27 1.27)
				)
				(justify mirror)
			)
		)
		(duplicate_pad_numbers_are_jumpers no)
		(pad "1" thru_hole circle
			(at 0 0 180)
			(size 0.4572 0.4572)
			(drill 0.20574)
			(layers "*.Cu" "*.Mask")
			(remove_unused_layers no)
			(net "DDR0_32A_A0")
			(clearance 0.1143)
			(thermal_gap 0.1143)
		)
	)
	(footprint ""
		(layer "B.Cu")
		(at 45.237019 9.542018)
		(property "Reference" "R322"
			(at 0 0 0)
			(layer "B.SilkS")
			(hide yes)
			(effects
				(font
					(size 1.27 1.27)
				)
				(justify mirror)
			)
		)
		(property "Value" ""
			(at 0 0 0)
			(layer "B.Fab")
			(effects
				(font
					(size 1.27 1.27)
				)
				(justify mirror)
			)
		)
		(duplicate_pad_numbers_are_jumpers no)
		(fp_circle
			(center 0 0)
			(end 0.104648 0)
			(stroke
				(width 0.1016)
				(type default)
			)
			(fill no)
			(layer "B.SilkS")
		)
		(fp_poly
			(pts
				(xy 0.381 -0.889) (xy 0.381 0.889) (xy -0.381 0.889) (xy -0.381 -0.889)
			)
			(stroke
				(width 0)
				(type default)
			)
			(fill no)
			(layer "B.CrtYd")
		)
		(fp_line
			(start -0.508 -1.016)
			(end -0.508 1.016)
			(stroke
				(width 0.0254)
				(type default)
			)
			(layer "B.Fab")
		)
		(fp_line
			(start -0.508 1.016)
			(end 0.508 1.016)
			(stroke
				(width 0.0254)
				(type default)
			)
			(layer "B.Fab")
		)
		(fp_line
			(start 0.254 -1.016)
			(end -0.508 -1.016)
			(stroke
				(width 0.0254)
				(type default)
			)
			(layer "B.Fab")
		)
		(fp_line
			(start 0.508 -1.016)
			(end 0.254 -1.016)
			(stroke
				(width 0.0254)
				(type default)
			)
			(layer "B.Fab")
		)
		(fp_line
			(start 0.508 1.016)
			(end 0.508 -1.016)
			(stroke
				(width 0.0254)
				(type default)
			)
			(layer "B.Fab")
		)
		(pad "1" smd custom
			(at 0 -0.500126 180)
			(size 0.127 0.127)
			(layers "B.Cu" "B.Mask" "B.Paste")
			(net "GND")
			(options
				(clearance outline)
				(anchor circle)
			)
			(primitives
				(gr_poly
					(pts
						(xy -0.1778 0.254) (xy 0.1778 0.254) (xy 0.254 0.1778) (xy 0.254 -0.1778) (xy 0.1778 -0.254) (xy -0.1778 -0.254)
						(xy -0.254 -0.1778) (xy -0.254 0.1778)
					)
					(width 0)
					(fill yes)
				)
			)
		)
		(pad "2" smd custom
			(at 0 0.500126 180)
			(size 0.127 0.127)
			(layers "B.Cu" "B.Mask" "B.Paste")
			(net "NFP_SERDES012_SYSCLK_IN_N")
			(options
				(clearance outline)
				(anchor circle)
			)
			(primitives
				(gr_poly
					(pts
						(xy -0.1778 0.254) (xy 0.1778 0.254) (xy 0.254 0.1778) (xy 0.254 -0.1778) (xy 0.1778 -0.254) (xy -0.1778 -0.254)
						(xy -0.254 -0.1778) (xy -0.254 0.1778)
					)
					(width 0)
					(fill yes)
				)
			)
		)
	)
	(footprint ""
		(layer "B.Cu")
		(at 47.736887 13.042138 -90)
		(property "Reference" "C172"
			(at 0 0 90)
			(layer "B.SilkS")
			(hide yes)
			(effects
				(font
					(size 1.27 1.27)
				)
				(justify mirror)
			)
		)
		(property "Value" ""
			(at 0 0 90)
			(layer "B.Fab")
			(effects
				(font
					(size 1.27 1.27)
				)
				(justify mirror)
			)
		)
		(duplicate_pad_numbers_are_jumpers no)
		(fp_circle
			(center 0 0)
			(end 0 -0.104648)
			(stroke
				(width 0.1016)
				(type default)
			)
			(fill no)
			(layer "B.SilkS")
		)
		(fp_poly
			(pts
				(xy 0.381 -0.889) (xy 0.381 0.889) (xy -0.381 0.889) (xy -0.381 -0.889)
			)
			(stroke
				(width 0)
				(type default)
			)
			(fill no)
			(layer "B.CrtYd")
		)
		(fp_line
			(start -0.508 1.016)
			(end 0.508 1.016)
			(stroke
				(width 0.0254)
				(type default)
			)
			(layer "B.Fab")
		)
		(fp_line
			(start 0.508 1.016)
			(end 0.508 -1.016)
			(stroke
				(width 0.0254)
				(type default)
			)
			(layer "B.Fab")
		)
		(fp_line
			(start -0.508 -1.016)
			(end -0.508 1.016)
			(stroke
				(width 0.0254)
				(type default)
			)
			(layer "B.Fab")
		)
		(fp_line
			(start 0.254 -1.016)
			(end -0.508 -1.016)
			(stroke
				(width 0.0254)
				(type default)
			)
			(layer "B.Fab")
		)
		(fp_line
			(start 0.508 -1.016)
			(end 0.254 -1.016)
			(stroke
				(width 0.0254)
				(type default)
			)
			(layer "B.Fab")
		)
		(pad "1" smd custom
			(at 0 -0.500126 90)
			(size 0.127 0.127)
			(layers "B.Cu" "B.Mask" "B.Paste")
			(net "VDDA_SERDES")
			(options
				(clearance outline)
				(anchor circle)
			)
			(primitives
				(gr_poly
					(pts
						(xy -0.1778 0.254) (xy 0.1778 0.254) (xy 0.254 0.1778) (xy 0.254 -0.1778) (xy 0.1778 -0.254) (xy -0.1778 -0.254)
						(xy -0.254 -0.1778) (xy -0.254 0.1778)
					)
					(width 0)
					(fill yes)
				)
			)
		)
		(pad "2" smd custom
			(at 0 0.500126 90)
			(size 0.127 0.127)
			(layers "B.Cu" "B.Mask" "B.Paste")
			(net "GND")
			(options
				(clearance outline)
				(anchor circle)
			)
			(primitives
				(gr_poly
					(pts
						(xy -0.1778 0.254) (xy 0.1778 0.254) (xy 0.254 0.1778) (xy 0.254 -0.1778) (xy 0.1778 -0.254) (xy -0.1778 -0.254)
						(xy -0.254 -0.1778) (xy -0.254 0.1778)
					)
					(width 0)
					(fill yes)
				)
			)
		)
	)
	(footprint ""
		(layer "B.Cu")
		(at 54.737 15.748)
		(property "Reference" "C5"
			(at 0.635 2.05867 0)
			(unlocked yes)
			(layer "B.SilkS")
			(effects
				(font
					(size 0.7874 0.5842)
					(thickness 0.127)
				)
				(justify left mirror)
			)
		)
		(property "Value" "22UF"
			(at 0.148158 1.7526 270)
			(unlocked yes)
			(layer "B.Fab")
			(hide yes)
			(effects
				(font
					(size 1.27 0.9652)
					(thickness 0.000001)
				)
				(justify left mirror)
			)
		)
		(property "Device Type" "CAPC0063"
			(at 0.148158 1.7526 270)
			(unlocked yes)
			(layer "B.Fab")
			(hide yes)
			(effects
				(font
					(size 1.27 0.9652)
					(thickness 0.000001)
				)
				(justify left mirror)
			)
		)
		(duplicate_pad_numbers_are_jumpers no)
		(fp_circle
			(center 0 0)
			(end 0.127 0)
			(stroke
				(width 0.2032)
				(type default)
			)
			(fill no)
			(layer "B.SilkS")
		)
		(fp_poly
			(pts
				(xy -0.7874 -1.6637) (xy 0.7874 -1.6637) (xy 0.7874 1.6637) (xy -0.7874 1.6637)
			)
			(stroke
				(width 0)
				(type default)
			)
			(fill no)
			(layer "B.CrtYd")
		)
		(fp_line
			(start -0.4064 -0.7874)
			(end -0.4064 0.8128)
			(stroke
				(width 0.0254)
				(type default)
			)
			(layer "B.Fab")
		)
		(fp_line
			(start -0.4064 0.8128)
			(end 0.4064 0.8128)
			(stroke
				(width 0.0254)
				(type default)
			)
			(layer "B.Fab")
		)
		(fp_line
			(start 0.4064 -0.7874)
			(end -0.4064 -0.7874)
			(stroke
				(width 0.0254)
				(type default)
			)
			(layer "B.Fab")
		)
		(fp_line
			(start 0.4064 0.8128)
			(end 0.4064 -0.7874)
			(stroke
				(width 0.0254)
				(type default)
			)
			(layer "B.Fab")
		)
		(pad "1" smd rect
			(at 0 -0.8001 180)
			(size 0.8636 0.9652)
			(layers "B.Cu" "B.Mask" "B.Paste")
			(net "VDD_CORE")
		)
		(pad "2" smd rect
			(at 0 0.8001 180)
			(size 0.8636 0.9652)
			(layers "B.Cu" "B.Mask" "B.Paste")
			(net "GND")
		)
		(zone
			(layer "B.Cu")
			(hatch none 0.5)
			(connect_pads
				(clearance 0)
			)
			(min_thickness 0.25)
			(keepout
				(tracks not_allowed)
				(vias allowed)
				(pads allowed)
				(copperpour not_allowed)
				(footprints allowed)
			)
			(placement
				(enabled no)
				(sheetname "")
			)
			(fill
				(thermal_gap 0.5)
				(thermal_bridge_width 0.5)
				(island_removal_mode 0)
			)
			(polygon
				(pts
					(xy 54.8005 15.494) (xy 54.6735 15.494) (xy 54.6735 16.002) (xy 54.8005 16.002)
				)
			)
		)
	)
	(footprint ""
		(layer "B.Cu")
		(at 55.88 45.593 90)
		(property "Reference" "TP37"
			(at -3.937 -0.66167 270)
			(unlocked yes)
			(layer "B.SilkS")
			(effects
				(font
					(size 0.7874 0.5842)
					(thickness 0.127)
				)
				(justify left mirror)
			)
		)
		(property "Value" "*"
			(at 0.4826 -0.14732 90)
			(unlocked yes)
			(layer "B.Fab")
			(hide yes)
			(effects
				(font
					(size 1.27 0.9652)
					(thickness 0.000001)
				)
				(justify left mirror)
			)
		)
		(property "Device Type" "TP_SMALL"
			(at 0.4826 -0.14732 90)
			(unlocked yes)
			(layer "B.Fab")
			(hide yes)
			(effects
				(font
					(size 1.27 0.9652)
					(thickness 0.000001)
				)
				(justify left mirror)
			)
		)
		(duplicate_pad_numbers_are_jumpers no)
		(fp_line
			(start 0.8636 -0.8636)
			(end 0.8636 0.8636)
			(stroke
				(width 0.1524)
				(type default)
			)
			(layer "B.SilkS")
		)
		(fp_line
			(start -0.8636 -0.8636)
			(end 0.8636 -0.8636)
			(stroke
				(width 0.1524)
				(type default)
			)
			(layer "B.SilkS")
		)
		(fp_line
			(start 0.8636 0.8636)
			(end -0.8636 0.8636)
			(stroke
				(width 0.1524)
				(type default)
			)
			(layer "B.SilkS")
		)
		(fp_line
			(start -0.8636 0.8636)
			(end -0.8636 -0.8636)
			(stroke
				(width 0.1524)
				(type default)
			)
			(layer "B.SilkS")
		)
		(fp_poly
			(pts
				(xy 0.635 -0.635) (xy 0.635 0.635) (xy -0.635 0.635) (xy -0.635 -0.635)
			)
			(stroke
				(width 0)
				(type default)
			)
			(fill no)
			(layer "B.CrtYd")
		)
		(pad "1" smd rect
			(at 0 0 270)
			(size 1.27 1.27)
			(layers "B.Cu" "B.Mask" "B.Paste")
			(net "VDD_CORE")
		)
	)
	(footprint ""
		(layer "B.Cu")
		(at 76.251003 14.256004)
		(property "Reference" "V_A-DQS2-N"
			(at 0 0 0)
			(layer "B.SilkS")
			(hide yes)
			(effects
				(font
					(size 1.27 1.27)
				)
				(justify mirror)
			)
		)
		(property "Value" ""
			(at 0 0 0)
			(layer "B.Fab")
			(effects
				(font
					(size 1.27 1.27)
				)
				(justify mirror)
			)
		)
		(duplicate_pad_numbers_are_jumpers no)
		(pad "1" thru_hole circle
			(at 0 0 180)
			(size 0.4572 0.4572)
			(drill 0.20574)
			(layers "*.Cu" "*.Mask")
			(remove_unused_layers no)
			(net "DDR0_32A_DQS2_N")
			(clearance 0.1143)
			(thermal_gap 0.1143)
		)
	)
	(footprint ""
		(layer "B.Cu")
		(at 67.236975 12.542012 180)
		(property "Reference" "C193"
			(at 0 0 0)
			(layer "B.SilkS")
			(hide yes)
			(effects
				(font
					(size 1.27 1.27)
				)
				(justify mirror)
			)
		)
		(property "Value" ""
			(at 0 0 0)
			(layer "B.Fab")
			(effects
				(font
					(size 1.27 1.27)
				)
				(justify mirror)
			)
		)
		(duplicate_pad_numbers_are_jumpers no)
		(fp_circle
			(center 0 0)
			(end -0.104648 0)
			(stroke
				(width 0.1016)
				(type default)
			)
			(fill no)
			(layer "B.SilkS")
		)
		(fp_poly
			(pts
				(xy 0.381 -0.889) (xy 0.381 0.889) (xy -0.381 0.889) (xy -0.381 -0.889)
			)
			(stroke
				(width 0)
				(type default)
			)
			(fill no)
			(layer "B.CrtYd")
		)
		(fp_line
			(start 0.508 1.016)
			(end 0.508 -1.016)
			(stroke
				(width 0.0254)
				(type default)
			)
			(layer "B.Fab")
		)
		(fp_line
			(start 0.508 -1.016)
			(end 0.254 -1.016)
			(stroke
				(width 0.0254)
				(type default)
			)
			(layer "B.Fab")
		)
		(fp_line
			(start 0.254 -1.016)
			(end -0.508 -1.016)
			(stroke
				(width 0.0254)
				(type default)
			)
			(layer "B.Fab")
		)
		(fp_line
			(start -0.508 1.016)
			(end 0.508 1.016)
			(stroke
				(width 0.0254)
				(type default)
			)
			(layer "B.Fab")
		)
		(fp_line
			(start -0.508 -1.016)
			(end -0.508 1.016)
			(stroke
				(width 0.0254)
				(type default)
			)
			(layer "B.Fab")
		)
		(pad "1" smd custom
			(at 0 -0.500126)
			(size 0.127 0.127)
			(layers "B.Cu" "B.Mask" "B.Paste")
			(net "DDR_VDDQ")
			(options
				(clearance outline)
				(anchor circle)
			)
			(primitives
				(gr_poly
					(pts
						(xy -0.1778 0.254) (xy 0.1778 0.254) (xy 0.254 0.1778) (xy 0.254 -0.1778) (xy 0.1778 -0.254) (xy -0.1778 -0.254)
						(xy -0.254 -0.1778) (xy -0.254 0.1778)
					)
					(width 0)
					(fill yes)
				)
			)
		)
		(pad "2" smd custom
			(at 0 0.500126)
			(size 0.127 0.127)
			(layers "B.Cu" "B.Mask" "B.Paste")
			(net "GND")
			(options
				(clearance outline)
				(anchor circle)
			)
			(primitives
				(gr_poly
					(pts
						(xy -0.1778 0.254) (xy 0.1778 0.254) (xy 0.254 0.1778) (xy 0.254 -0.1778) (xy 0.1778 -0.254) (xy -0.1778 -0.254)
						(xy -0.254 -0.1778) (xy -0.254 0.1778)
					)
					(width 0)
					(fill yes)
				)
			)
		)
	)
	(footprint ""
		(layer "B.Cu")
		(at 24.13 2.794)
		(property "Reference" "R370"
			(at 0.98933 1.524 270)
			(unlocked yes)
			(layer "B.SilkS")
			(effects
				(font
					(size 0.7874 0.5842)
					(thickness 0.127)
				)
				(justify left mirror)
			)
		)
		(property "Value" "4.75K"
			(at 0.148158 1.3462 270)
			(unlocked yes)
			(layer "B.Fab")
			(hide yes)
			(effects
				(font
					(size 1.27 0.9652)
					(thickness 0.000001)
				)
				(justify left mirror)
			)
		)
		(property "Device Type" "REST4024"
			(at 0.148158 1.3462 270)
			(unlocked yes)
			(layer "B.Fab")
			(hide yes)
			(effects
				(font
					(size 1.27 0.9652)
					(thickness 0.000001)
				)
				(justify left mirror)
			)
		)
		(duplicate_pad_numbers_are_jumpers no)
		(fp_poly
			(pts
				(xy -0.635 1.0668) (xy -0.635 -1.0668) (xy 0.635 -1.0668) (xy 0.635 1.0668)
			)
			(stroke
				(width 0)
				(type default)
			)
			(fill no)
			(layer "B.CrtYd")
		)
		(fp_line
			(start -0.254 -0.508)
			(end -0.254 0.508)
			(stroke
				(width 0.0254)
				(type default)
			)
			(layer "B.Fab")
		)
		(fp_line
			(start -0.254 0.508)
			(end 0.254 0.508)
			(stroke
				(width 0.0254)
				(type default)
			)
			(layer "B.Fab")
		)
		(fp_line
			(start 0.254 -0.508)
			(end -0.254 -0.508)
			(stroke
				(width 0.0254)
				(type default)
			)
			(layer "B.Fab")
		)
		(fp_line
			(start 0.254 0.508)
			(end 0.254 -0.508)
			(stroke
				(width 0.0254)
				(type default)
			)
			(layer "B.Fab")
		)
		(pad "1" smd rect
			(at 0 -0.4191 180)
			(size 0.508 0.5334)
			(layers "B.Cu" "B.Mask" "B.Paste")
			(net "NFP_SMBUS_SCL")
		)
		(pad "2" smd rect
			(at 0 0.4191 180)
			(size 0.508 0.5334)
			(layers "B.Cu" "B.Mask" "B.Paste")
			(net "EXT_3.3V")
		)
		(zone
			(layer "B.Cu")
			(hatch none 0.5)
			(connect_pads
				(clearance 0)
			)
			(min_thickness 0.25)
			(keepout
				(tracks not_allowed)
				(vias allowed)
				(pads allowed)
				(copperpour not_allowed)
				(footprints allowed)
			)
			(placement
				(enabled no)
				(sheetname "")
			)
			(fill
				(thermal_gap 0.5)
				(thermal_bridge_width 0.5)
				(island_removal_mode 0)
			)
			(polygon
				(pts
					(xy 24.1046 2.7686) (xy 24.1046 2.8194) (xy 24.1554 2.8194) (xy 24.1554 2.7686)
				)
			)
		)
	)
)
